# T6G (Grand Teton) — schematic netlist excerpt (pin names and nets, part order shuffled) for the footprints in the layout excerpt that follows; sources: Cadence DE-HDL packaged netlist, KiCad conversion of 04192023_DAF0TMB3IC0_F0TG_MB_C_brd_V02_OCP.brd

C2035  Q_CAP  1UF 25V 10% X6S  pkg C0402  page 234 : A = P3V3_AUX_USB_HUB ; B = GND
PC215_1  Q_CAP  22UF 16V 20% X6S  pkg C0805  page 208 : A = SW_P12V_AUX_PVDD11_S3_P0_FLT ; B = GND
R1816  Q_RES  0 5% CHIP  pkg 0402LF  page 150 : A = PWRGD_PS_PWROK ; B = PWRGD_PS_PWROK_R

(kicad_pcb
	(version 20260206)
	(generator "pcbnew")
	(generator_version "10.0")
	(general
		(thickness 1.6)
		(legacy_teardrops no)
	)
	(paper "A4")
	(title_block
		(title "04192023_DAF0TMB3IC0_F0TG_MB_C_brd_V02_OCP.brd")
		(comment 1 "Grand Teton / footprints 5632-5634 of 8354")
	)
	(layers
		(0 "F.Cu" signal "TOP")
		(4 "In1.Cu" signal "GND")
		(6 "In2.Cu" signal "IN1")
		(8 "In3.Cu" signal "GND1")
		(10 "In4.Cu" signal "IN2")
		(12 "In5.Cu" signal "GND2")
		(14 "In6.Cu" signal "IN3")
		(16 "In7.Cu" signal "GND3")
		(18 "In8.Cu" signal "VCC")
		(20 "In9.Cu" signal "VCC1")
		(22 "In10.Cu" signal "GND4")
		(24 "In11.Cu" signal "IN4")
		(26 "In12.Cu" signal "GND5")
		(28 "In13.Cu" signal "IN5")
		(30 "In14.Cu" signal "GND6")
		(32 "In15.Cu" signal "IN6")
		(34 "In16.Cu" signal "GND7")
		(2 "B.Cu" signal "BOTTOM")
		(9 "F.Adhes" user "F.Adhesive")
		(11 "B.Adhes" user "B.Adhesive")
		(13 "F.Paste" user "Package Geometry/Pastemask Top")
		(15 "B.Paste" user "Package Geometry/Pastemask Bottom")
		(5 "F.SilkS" user "Ref Des/Silkscreen Top")
		(7 "B.SilkS" user "Ref Des/Silkscreen Bottom")
		(1 "F.Mask" user "Board Geometry/Soldermask Top")
		(3 "B.Mask" user "Board Geometry/Soldermask Bottom")
		(17 "Dwgs.User" user "User.Drawings")
		(19 "Cmts.User" user "User.Comments")
		(21 "Eco1.User" user "User.Eco1")
		(23 "Eco2.User" user "User.Eco2")
		(25 "Edge.Cuts" user "Board Geometry/Outline")
		(27 "Margin" user)
		(31 "F.CrtYd" user "Package Geometry/Place Bound Top")
		(29 "B.CrtYd" user "Package Geometry/Place Bound Bottom")
		(35 "F.Fab" user "Ref Des/Assembly Top")
		(33 "B.Fab" user "Ref Des/Assembly Bottom")
	)
	(footprint ""
		(layer "B.Cu")
		(at 145.3388 -13.762228 90)
		(property "Reference" "R1816"
			(at 0 0 90)
			(layer "B.SilkS")
			(hide yes)
			(effects
				(font
					(size 1.27 1.27)
				)
				(justify mirror)
			)
		)
		(property "Value" ""
			(at 0 0 90)
			(layer "B.Fab")
			(effects
				(font
					(size 1.27 1.27)
				)
				(justify mirror)
			)
		)
		(duplicate_pad_numbers_are_jumpers no)
		(fp_line
			(start 0.7874 -0.4064)
			(end -0.7874 -0.4064)
			(stroke
				(width 0.1524)
				(type default)
			)
			(layer "B.SilkS")
		)
		(fp_line
			(start -0.7874 -0.4064)
			(end -0.7874 0.4064)
			(stroke
				(width 0.1524)
				(type default)
			)
			(layer "B.SilkS")
		)
		(fp_line
			(start 0.7874 0.4064)
			(end 0.7874 -0.4064)
			(stroke
				(width 0.1524)
				(type default)
			)
			(layer "B.SilkS")
		)
		(fp_line
			(start -0.7874 0.4064)
			(end 0.7874 0.4064)
			(stroke
				(width 0.1524)
				(type default)
			)
			(layer "B.SilkS")
		)
		(fp_line
			(start 0.67945 -0.305054)
			(end 0.12065 -0.305054)
			(stroke
				(width 0.1)
				(type default)
			)
			(layer "B.Fab")
		)
		(fp_line
			(start 0.12065 -0.305054)
			(end 0.12065 -0.2794)
			(stroke
				(width 0.1)
				(type default)
			)
			(layer "B.Fab")
		)
		(fp_line
			(start -0.12065 -0.3048)
			(end -0.67945 -0.3048)
			(stroke
				(width 0.1)
				(type default)
			)
			(layer "B.Fab")
		)
		(fp_line
			(start -0.67945 -0.3048)
			(end -0.67945 0.3048)
			(stroke
				(width 0.1)
				(type default)
			)
			(layer "B.Fab")
		)
		(fp_line
			(start 0.12065 -0.2794)
			(end -0.12065 -0.2794)
			(stroke
				(width 0.1)
				(type default)
			)
			(layer "B.Fab")
		)
		(fp_line
			(start -0.12065 -0.2794)
			(end -0.12065 -0.3048)
			(stroke
				(width 0.1)
				(type default)
			)
			(layer "B.Fab")
		)
		(fp_line
			(start 0.12065 0.2794)
			(end 0.12065 0.3048)
			(stroke
				(width 0.1)
				(type default)
			)
			(layer "B.Fab")
		)
		(fp_line
			(start -0.120396 0.2794)
			(end 0.12065 0.2794)
			(stroke
				(width 0.1)
				(type default)
			)
			(layer "B.Fab")
		)
		(fp_line
			(start 0.67945 0.3048)
			(end 0.67945 -0.305054)
			(stroke
				(width 0.1)
				(type default)
			)
			(layer "B.Fab")
		)
		(fp_line
			(start 0.12065 0.3048)
			(end 0.67945 0.3048)
			(stroke
				(width 0.1)
				(type default)
			)
			(layer "B.Fab")
		)
		(fp_line
			(start -0.120396 0.3048)
			(end -0.120396 0.2794)
			(stroke
				(width 0.1)
				(type default)
			)
			(layer "B.Fab")
		)
		(fp_line
			(start -0.67945 0.3048)
			(end -0.120396 0.3048)
			(stroke
				(width 0.1)
				(type default)
			)
			(layer "B.Fab")
		)
		(pad "1" smd circle
			(at 0.40005 0 270)
			(size 0 0)
			(layers "B.Cu" "B.Mask" "B.Paste")
			(net "PWRGD_PS_PWROK")
		)
		(pad "2" smd circle
			(at -0.40005 0 270)
			(size 0 0)
			(layers "B.Cu" "B.Mask" "B.Paste")
			(net "PWRGD_PS_PWROK_R")
		)
	)
	(footprint ""
		(layer "B.Cu")
		(at 14.616176 -101.217984 90)
		(property "Reference" "C2035"
			(at 0 0 90)
			(layer "B.SilkS")
			(hide yes)
			(effects
				(font
					(size 1.27 1.27)
				)
				(justify mirror)
			)
		)
		(property "Value" ""
			(at 0 0 90)
			(layer "B.Fab")
			(effects
				(font
					(size 1.27 1.27)
				)
				(justify mirror)
			)
		)
		(duplicate_pad_numbers_are_jumpers no)
		(fp_line
			(start 0.7874 -0.4064)
			(end -0.7874 -0.4064)
			(stroke
				(width 0.1524)
				(type default)
			)
			(layer "B.SilkS")
		)
		(fp_line
			(start -0.7874 -0.4064)
			(end -0.7874 0.4064)
			(stroke
				(width 0.1524)
				(type default)
			)
			(layer "B.SilkS")
		)
		(fp_line
			(start 0.7874 0.4064)
			(end 0.7874 -0.4064)
			(stroke
				(width 0.1524)
				(type default)
			)
			(layer "B.SilkS")
		)
		(fp_line
			(start -0.7874 0.4064)
			(end 0.7874 0.4064)
			(stroke
				(width 0.1524)
				(type default)
			)
			(layer "B.SilkS")
		)
		(fp_line
			(start 0.67945 -0.305054)
			(end 0.12065 -0.305054)
			(stroke
				(width 0.1)
				(type default)
			)
			(layer "B.Fab")
		)
		(fp_line
			(start 0.12065 -0.305054)
			(end 0.12065 -0.2794)
			(stroke
				(width 0.1)
				(type default)
			)
			(layer "B.Fab")
		)
		(fp_line
			(start -0.12065 -0.3048)
			(end -0.67945 -0.3048)
			(stroke
				(width 0.1)
				(type default)
			)
			(layer "B.Fab")
		)
		(fp_line
			(start -0.67945 -0.3048)
			(end -0.67945 0.3048)
			(stroke
				(width 0.1)
				(type default)
			)
			(layer "B.Fab")
		)
		(fp_line
			(start 0.12065 -0.2794)
			(end -0.12065 -0.2794)
			(stroke
				(width 0.1)
				(type default)
			)
			(layer "B.Fab")
		)
		(fp_line
			(start -0.12065 -0.2794)
			(end -0.12065 -0.3048)
			(stroke
				(width 0.1)
				(type default)
			)
			(layer "B.Fab")
		)
		(fp_line
			(start 0.12065 0.2794)
			(end 0.12065 0.3048)
			(stroke
				(width 0.1)
				(type default)
			)
			(layer "B.Fab")
		)
		(fp_line
			(start -0.120396 0.2794)
			(end 0.12065 0.2794)
			(stroke
				(width 0.1)
				(type default)
			)
			(layer "B.Fab")
		)
		(fp_line
			(start 0.67945 0.3048)
			(end 0.67945 -0.305054)
			(stroke
				(width 0.1)
				(type default)
			)
			(layer "B.Fab")
		)
		(fp_line
			(start 0.12065 0.3048)
			(end 0.67945 0.3048)
			(stroke
				(width 0.1)
				(type default)
			)
			(layer "B.Fab")
		)
		(fp_line
			(start -0.120396 0.3048)
			(end -0.120396 0.2794)
			(stroke
				(width 0.1)
				(type default)
			)
			(layer "B.Fab")
		)
		(fp_line
			(start -0.67945 0.3048)
			(end -0.120396 0.3048)
			(stroke
				(width 0.1)
				(type default)
			)
			(layer "B.Fab")
		)
		(pad "1" smd circle
			(at 0.40005 0 270)
			(size 0 0)
			(layers "B.Cu" "B.Mask" "B.Paste")
			(net "P3V3_AUX_USB_HUB")
		)
		(pad "2" smd circle
			(at -0.40005 0 270)
			(size 0 0)
			(layers "B.Cu" "B.Mask" "B.Paste")
			(net "GND")
		)
	)
	(footprint ""
		(layer "B.Cu")
		(at 424.848782 -354.87229 -90)
		(property "Reference" "PC215_1"
			(at 0 0 90)
			(layer "B.SilkS")
			(hide yes)
			(effects
				(font
					(size 1.27 1.27)
				)
				(justify mirror)
			)
		)
		(property "Value" ""
			(at 0 0 90)
			(layer "B.Fab")
			(effects
				(font
					(size 1.27 1.27)
				)
				(justify mirror)
			)
		)
		(duplicate_pad_numbers_are_jumpers no)
		(fp_line
			(start -1.524 0.762)
			(end 1.524 0.762)
			(stroke
				(width 0.1524)
				(type default)
			)
			(layer "B.SilkS")
		)
		(fp_line
			(start 1.524 0.762)
			(end 1.524 -0.762)
			(stroke
				(width 0.1524)
				(type default)
			)
			(layer "B.SilkS")
		)
		(fp_line
			(start -1.524 -0.762)
			(end -1.524 0.762)
			(stroke
				(width 0.1524)
				(type default)
			)
			(layer "B.SilkS")
		)
		(fp_line
			(start 1.524 -0.762)
			(end -1.524 -0.762)
			(stroke
				(width 0.1524)
				(type default)
			)
			(layer "B.SilkS")
		)
		(fp_line
			(start -1.1049 0.724916)
			(end -1.1049 -0.724916)
			(stroke
				(width 0.1)
				(type default)
			)
			(layer "B.Fab")
		)
		(fp_line
			(start 1.1049 0.724916)
			(end -1.1049 0.724916)
			(stroke
				(width 0.1)
				(type default)
			)
			(layer "B.Fab")
		)
		(fp_line
			(start -1.1049 -0.724916)
			(end 1.1049 -0.724916)
			(stroke
				(width 0.1)
				(type default)
			)
			(layer "B.Fab")
		)
		(fp_line
			(start 1.1049 -0.724916)
			(end 1.1049 0.724916)
			(stroke
				(width 0.1)
				(type default)
			)
			(layer "B.Fab")
		)
		(pad "1" smd rect
			(at 0.889 0 270)
			(size 1.016 1.27)
			(layers "B.Cu" "B.Mask" "B.Paste")
			(net "SW_P12V_AUX_PVDD11_S3_P0_FLT")
		)
		(pad "2" smd rect
			(at -0.889 0 270)
			(size 1.016 1.27)
			(layers "B.Cu" "B.Mask" "B.Paste")
			(net "GND")
		)
	)
)
